(kicad_pcb
	(version 20260206)
	(generator "pcbnew")
	(generator_version "10.0")
	(general
		(thickness 1.6)
		(legacy_teardrops no)
	)
	(paper "A4")
	(title_block
		(title "01162023_DA0F0TEBIF0_F0T_Expander_BD_F_brd_V02_OCP.brd")
		(comment 1 "Grand Teton / footprints 9539-9547 of 9728")
	)
	(layers
		(0 "F.Cu" signal "TOP")
		(4 "In1.Cu" signal "GND")
		(6 "In2.Cu" signal "VCC")
		(8 "In3.Cu" signal "VCC1")
		(10 "In4.Cu" signal "GND1")
		(12 "In5.Cu" signal "IN1")
		(14 "In6.Cu" signal "GND2")
		(16 "In7.Cu" signal "IN2")
		(18 "In8.Cu" signal "GND3")
		(20 "In9.Cu" signal "IN3")
		(22 "In10.Cu" signal "GND4")
		(24 "In11.Cu" signal "IN4")
		(26 "In12.Cu" signal "GND5")
		(28 "In13.Cu" signal "IN5")
		(30 "In14.Cu" signal "GND6")
		(32 "In15.Cu" signal "IN6")
		(34 "In16.Cu" signal "GND7")
		(2 "B.Cu" signal "BOTTOM")
		(9 "F.Adhes" user "F.Adhesive")
		(11 "B.Adhes" user "B.Adhesive")
		(13 "F.Paste" user "Package Geometry/Pastemask Top")
		(15 "B.Paste" user "Package Geometry/Pastemask Bottom")
		(5 "F.SilkS" user "Ref Des/Silkscreen Top")
		(7 "B.SilkS" user "Ref Des/Silkscreen Bottom")
		(1 "F.Mask" user "Board Geometry/Soldermask Top")
		(3 "B.Mask" user "Board Geometry/Soldermask Bottom")
		(17 "Dwgs.User" user "User.Drawings")
		(19 "Cmts.User" user "User.Comments")
		(21 "Eco1.User" user "User.Eco1")
		(23 "Eco2.User" user "User.Eco2")
		(25 "Edge.Cuts" user "Board Geometry/Outline")
		(27 "Margin" user)
		(31 "F.CrtYd" user "Package Geometry/Place Bound Top")
		(29 "B.CrtYd" user "Package Geometry/Place Bound Bottom")
		(35 "F.Fab" user "Ref Des/Assembly Top")
		(33 "B.Fab" user "Ref Des/Assembly Bottom")
	)
	(footprint ""
		(layer "B.Cu")
		(at 223.338644 -231.225598 -90)
		(property "Reference" "R1480"
			(at 0 0 90)
			(layer "B.SilkS")
			(hide yes)
			(effects
				(font
					(size 1.27 1.27)
				)
				(justify mirror)
			)
		)
		(property "Value" ""
			(at 0 0 90)
			(layer "B.Fab")
			(effects
				(font
					(size 1.27 1.27)
				)
				(justify mirror)
			)
		)
		(duplicate_pad_numbers_are_jumpers no)
		(fp_line
			(start -0.7874 0.4064)
			(end 0.7874 0.4064)
			(stroke
				(width 0.1524)
				(type default)
			)
			(layer "B.SilkS")
		)
		(fp_line
			(start 0.7874 0.4064)
			(end 0.7874 -0.4064)
			(stroke
				(width 0.1524)
				(type default)
			)
			(layer "B.SilkS")
		)
		(fp_line
			(start -0.7874 -0.4064)
			(end -0.7874 0.4064)
			(stroke
				(width 0.1524)
				(type default)
			)
			(layer "B.SilkS")
		)
		(fp_line
			(start 0.7874 -0.4064)
			(end -0.7874 -0.4064)
			(stroke
				(width 0.1524)
				(type default)
			)
			(layer "B.SilkS")
		)
		(fp_line
			(start -0.67945 0.3048)
			(end -0.120396 0.3048)
			(stroke
				(width 0.1)
				(type default)
			)
			(layer "B.Fab")
		)
		(fp_line
			(start -0.120396 0.3048)
			(end -0.120396 0.2794)
			(stroke
				(width 0.1)
				(type default)
			)
			(layer "B.Fab")
		)
		(fp_line
			(start 0.12065 0.3048)
			(end 0.67945 0.3048)
			(stroke
				(width 0.1)
				(type default)
			)
			(layer "B.Fab")
		)
		(fp_line
			(start 0.67945 0.3048)
			(end 0.67945 -0.305054)
			(stroke
				(width 0.1)
				(type default)
			)
			(layer "B.Fab")
		)
		(fp_line
			(start -0.120396 0.2794)
			(end 0.12065 0.2794)
			(stroke
				(width 0.1)
				(type default)
			)
			(layer "B.Fab")
		)
		(fp_line
			(start 0.12065 0.2794)
			(end 0.12065 0.3048)
			(stroke
				(width 0.1)
				(type default)
			)
			(layer "B.Fab")
		)
		(fp_line
			(start -0.12065 -0.2794)
			(end -0.12065 -0.3048)
			(stroke
				(width 0.1)
				(type default)
			)
			(layer "B.Fab")
		)
		(fp_line
			(start 0.12065 -0.2794)
			(end -0.12065 -0.2794)
			(stroke
				(width 0.1)
				(type default)
			)
			(layer "B.Fab")
		)
		(fp_line
			(start -0.67945 -0.3048)
			(end -0.67945 0.3048)
			(stroke
				(width 0.1)
				(type default)
			)
			(layer "B.Fab")
		)
		(fp_line
			(start -0.12065 -0.3048)
			(end -0.67945 -0.3048)
			(stroke
				(width 0.1)
				(type default)
			)
			(layer "B.Fab")
		)
		(fp_line
			(start 0.12065 -0.305054)
			(end 0.12065 -0.2794)
			(stroke
				(width 0.1)
				(type default)
			)
			(layer "B.Fab")
		)
		(fp_line
			(start 0.67945 -0.305054)
			(end 0.12065 -0.305054)
			(stroke
				(width 0.1)
				(type default)
			)
			(layer "B.Fab")
		)
		(pad "1" smd circle
			(at 0.40005 0 90)
			(size 0 0)
			(layers "B.Cu" "B.Mask" "B.Paste")
			(net "SMB_NIC1_SDA")
		)
		(pad "2" smd circle
			(at -0.40005 0 90)
			(size 0 0)
			(layers "B.Cu" "B.Mask" "B.Paste")
			(net "SMB_NIC1_R_SDA")
		)
	)
	(footprint ""
		(layer "B.Cu")
		(at 171.949872 -303.499774 -90)
		(property "Reference" "C3081"
			(at 0 0 90)
			(layer "B.SilkS")
			(hide yes)
			(effects
				(font
					(size 1.27 1.27)
				)
				(justify mirror)
			)
		)
		(property "Value" ""
			(at 0 0 90)
			(layer "B.Fab")
			(effects
				(font
					(size 1.27 1.27)
				)
				(justify mirror)
			)
		)
		(duplicate_pad_numbers_are_jumpers no)
		(fp_line
			(start -0.299974 0.150114)
			(end 0.299974 0.150114)
			(stroke
				(width 0.1)
				(type default)
			)
			(layer "B.Fab")
		)
		(fp_line
			(start 0.299974 0.150114)
			(end 0.299974 -0.150114)
			(stroke
				(width 0.1)
				(type default)
			)
			(layer "B.Fab")
		)
		(fp_line
			(start -0.299974 -0.150114)
			(end -0.299974 0.150114)
			(stroke
				(width 0.1)
				(type default)
			)
			(layer "B.Fab")
		)
		(fp_line
			(start 0.299974 -0.150114)
			(end -0.299974 -0.150114)
			(stroke
				(width 0.1)
				(type default)
			)
			(layer "B.Fab")
		)
		(pad "1" smd rect
			(at 0.2667 0 90)
			(size 0.3048 0.381)
			(layers "B.Cu" "B.Mask" "B.Paste")
			(net "P1V25_PEX1")
		)
		(pad "2" smd rect
			(at -0.2667 0 90)
			(size 0.3048 0.381)
			(layers "B.Cu" "B.Mask" "B.Paste")
			(net "GND")
		)
	)
	(footprint ""
		(layer "B.Cu")
		(at 337.439 -207.772 90)
		(property "Reference" "R4131"
			(at 0 0 90)
			(layer "B.SilkS")
			(hide yes)
			(effects
				(font
					(size 1.27 1.27)
				)
				(justify mirror)
			)
		)
		(property "Value" ""
			(at 0 0 90)
			(layer "B.Fab")
			(effects
				(font
					(size 1.27 1.27)
				)
				(justify mirror)
			)
		)
		(duplicate_pad_numbers_are_jumpers no)
		(fp_line
			(start 0.7874 -0.4064)
			(end -0.7874 -0.4064)
			(stroke
				(width 0.1524)
				(type default)
			)
			(layer "B.SilkS")
		)
		(fp_line
			(start -0.7874 -0.4064)
			(end -0.7874 0.4064)
			(stroke
				(width 0.1524)
				(type default)
			)
			(layer "B.SilkS")
		)
		(fp_line
			(start 0.7874 0.4064)
			(end 0.7874 -0.4064)
			(stroke
				(width 0.1524)
				(type default)
			)
			(layer "B.SilkS")
		)
		(fp_line
			(start -0.7874 0.4064)
			(end 0.7874 0.4064)
			(stroke
				(width 0.1524)
				(type default)
			)
			(layer "B.SilkS")
		)
		(fp_line
			(start 0.67945 -0.305054)
			(end 0.12065 -0.305054)
			(stroke
				(width 0.1)
				(type default)
			)
			(layer "B.Fab")
		)
		(fp_line
			(start 0.12065 -0.305054)
			(end 0.12065 -0.2794)
			(stroke
				(width 0.1)
				(type default)
			)
			(layer "B.Fab")
		)
		(fp_line
			(start -0.12065 -0.3048)
			(end -0.67945 -0.3048)
			(stroke
				(width 0.1)
				(type default)
			)
			(layer "B.Fab")
		)
		(fp_line
			(start -0.67945 -0.3048)
			(end -0.67945 0.3048)
			(stroke
				(width 0.1)
				(type default)
			)
			(layer "B.Fab")
		)
		(fp_line
			(start 0.12065 -0.2794)
			(end -0.12065 -0.2794)
			(stroke
				(width 0.1)
				(type default)
			)
			(layer "B.Fab")
		)
		(fp_line
			(start -0.12065 -0.2794)
			(end -0.12065 -0.3048)
			(stroke
				(width 0.1)
				(type default)
			)
			(layer "B.Fab")
		)
		(fp_line
			(start 0.12065 0.2794)
			(end 0.12065 0.3048)
			(stroke
				(width 0.1)
				(type default)
			)
			(layer "B.Fab")
		)
		(fp_line
			(start -0.120396 0.2794)
			(end 0.12065 0.2794)
			(stroke
				(width 0.1)
				(type default)
			)
			(layer "B.Fab")
		)
		(fp_line
			(start 0.67945 0.3048)
			(end 0.67945 -0.305054)
			(stroke
				(width 0.1)
				(type default)
			)
			(layer "B.Fab")
		)
		(fp_line
			(start 0.12065 0.3048)
			(end 0.67945 0.3048)
			(stroke
				(width 0.1)
				(type default)
			)
			(layer "B.Fab")
		)
		(fp_line
			(start -0.120396 0.3048)
			(end -0.120396 0.2794)
			(stroke
				(width 0.1)
				(type default)
			)
			(layer "B.Fab")
		)
		(fp_line
			(start -0.67945 0.3048)
			(end -0.120396 0.3048)
			(stroke
				(width 0.1)
				(type default)
			)
			(layer "B.Fab")
		)
		(pad "1" smd circle
			(at 0.40005 0 270)
			(size 0 0)
			(layers "B.Cu" "B.Mask" "B.Paste")
			(net "SSD12_PWR_EN")
		)
		(pad "2" smd circle
			(at -0.40005 0 270)
			(size 0 0)
			(layers "B.Cu" "B.Mask" "B.Paste")
			(net "SSD12_PWR_EN_R")
		)
	)
	(footprint ""
		(layer "B.Cu")
		(at 165.299898 -288.774886 180)
		(property "Reference" "C3185"
			(at 0 0 0)
			(layer "B.SilkS")
			(hide yes)
			(effects
				(font
					(size 1.27 1.27)
				)
				(justify mirror)
			)
		)
		(property "Value" ""
			(at 0 0 0)
			(layer "B.Fab")
			(effects
				(font
					(size 1.27 1.27)
				)
				(justify mirror)
			)
		)
		(duplicate_pad_numbers_are_jumpers no)
		(fp_line
			(start 0.299974 0.150114)
			(end 0.299974 -0.150114)
			(stroke
				(width 0.1)
				(type default)
			)
			(layer "B.Fab")
		)
		(fp_line
			(start 0.299974 -0.150114)
			(end -0.299974 -0.150114)
			(stroke
				(width 0.1)
				(type default)
			)
			(layer "B.Fab")
		)
		(fp_line
			(start -0.299974 0.150114)
			(end 0.299974 0.150114)
			(stroke
				(width 0.1)
				(type default)
			)
			(layer "B.Fab")
		)
		(fp_line
			(start -0.299974 -0.150114)
			(end -0.299974 0.150114)
			(stroke
				(width 0.1)
				(type default)
			)
			(layer "B.Fab")
		)
		(pad "1" smd rect
			(at 0.2667 0)
			(size 0.3048 0.381)
			(layers "B.Cu" "B.Mask" "B.Paste")
			(net "P1V8_VDDA_PEX1")
		)
		(pad "2" smd rect
			(at -0.2667 0)
			(size 0.3048 0.381)
			(layers "B.Cu" "B.Mask" "B.Paste")
			(net "GND")
		)
	)
	(footprint ""
		(layer "B.Cu")
		(at 58.699908 -292.099746 90)
		(property "Reference" "C1165"
			(at 0 0 90)
			(layer "B.SilkS")
			(hide yes)
			(effects
				(font
					(size 1.27 1.27)
				)
				(justify mirror)
			)
		)
		(property "Value" ""
			(at 0 0 90)
			(layer "B.Fab")
			(effects
				(font
					(size 1.27 1.27)
				)
				(justify mirror)
			)
		)
		(duplicate_pad_numbers_are_jumpers no)
		(fp_line
			(start 0.299974 -0.150114)
			(end -0.299974 -0.150114)
			(stroke
				(width 0.1)
				(type default)
			)
			(layer "B.Fab")
		)
		(fp_line
			(start -0.299974 -0.150114)
			(end -0.299974 0.150114)
			(stroke
				(width 0.1)
				(type default)
			)
			(layer "B.Fab")
		)
		(fp_line
			(start 0.299974 0.150114)
			(end 0.299974 -0.150114)
			(stroke
				(width 0.1)
				(type default)
			)
			(layer "B.Fab")
		)
		(fp_line
			(start -0.299974 0.150114)
			(end 0.299974 0.150114)
			(stroke
				(width 0.1)
				(type default)
			)
			(layer "B.Fab")
		)
		(pad "1" smd rect
			(at 0.2667 0 270)
			(size 0.3048 0.381)
			(layers "B.Cu" "B.Mask" "B.Paste")
			(net "P0V8_SERDES_VDDA_PEX0")
		)
		(pad "2" smd rect
			(at -0.2667 0 270)
			(size 0.3048 0.381)
			(layers "B.Cu" "B.Mask" "B.Paste")
			(net "GND")
		)
	)
	(footprint ""
		(layer "B.Cu")
		(at 127.748284 -284.796738 -90)
		(property "Reference" "PC110"
			(at 0 0 90)
			(layer "B.SilkS")
			(hide yes)
			(effects
				(font
					(size 1.27 1.27)
				)
				(justify mirror)
			)
		)
		(property "Value" ""
			(at 0 0 90)
			(layer "B.Fab")
			(effects
				(font
					(size 1.27 1.27)
				)
				(justify mirror)
			)
		)
		(duplicate_pad_numbers_are_jumpers no)
		(fp_line
			(start -1.524 0.762)
			(end 1.524 0.762)
			(stroke
				(width 0.1524)
				(type default)
			)
			(layer "B.SilkS")
		)
		(fp_line
			(start 1.524 0.762)
			(end 1.524 -0.762)
			(stroke
				(width 0.1524)
				(type default)
			)
			(layer "B.SilkS")
		)
		(fp_line
			(start -1.524 -0.762)
			(end -1.524 0.762)
			(stroke
				(width 0.1524)
				(type default)
			)
			(layer "B.SilkS")
		)
		(fp_line
			(start 1.524 -0.762)
			(end -1.524 -0.762)
			(stroke
				(width 0.1524)
				(type default)
			)
			(layer "B.SilkS")
		)
		(fp_line
			(start -1.1049 0.724916)
			(end -1.1049 -0.724916)
			(stroke
				(width 0.1)
				(type default)
			)
			(layer "B.Fab")
		)
		(fp_line
			(start 1.1049 0.724916)
			(end -1.1049 0.724916)
			(stroke
				(width 0.1)
				(type default)
			)
			(layer "B.Fab")
		)
		(fp_line
			(start -1.1049 -0.724916)
			(end 1.1049 -0.724916)
			(stroke
				(width 0.1)
				(type default)
			)
			(layer "B.Fab")
		)
		(fp_line
			(start 1.1049 -0.724916)
			(end 1.1049 0.724916)
			(stroke
				(width 0.1)
				(type default)
			)
			(layer "B.Fab")
		)
		(pad "1" smd rect
			(at 0.889 0 270)
			(size 1.016 1.27)
			(layers "B.Cu" "B.Mask" "B.Paste")
			(net "SW_P12V_P0V8_PEX1_FLT")
		)
		(pad "2" smd rect
			(at -0.889 0 270)
			(size 1.016 1.27)
			(layers "B.Cu" "B.Mask" "B.Paste")
			(net "GND")
		)
	)
	(footprint ""
		(layer "B.Cu")
		(at 139.36091 -214.964772 90)
		(property "Reference" "R989"
			(at 0 0 90)
			(layer "B.SilkS")
			(hide yes)
			(effects
				(font
					(size 1.27 1.27)
				)
				(justify mirror)
			)
		)
		(property "Value" ""
			(at 0 0 90)
			(layer "B.Fab")
			(effects
				(font
					(size 1.27 1.27)
				)
				(justify mirror)
			)
		)
		(duplicate_pad_numbers_are_jumpers no)
		(fp_line
			(start 0.7874 -0.4064)
			(end -0.7874 -0.4064)
			(stroke
				(width 0.1524)
				(type default)
			)
			(layer "B.SilkS")
		)
		(fp_line
			(start -0.7874 -0.4064)
			(end -0.7874 0.4064)
			(stroke
				(width 0.1524)
				(type default)
			)
			(layer "B.SilkS")
		)
		(fp_line
			(start 0.7874 0.4064)
			(end 0.7874 -0.4064)
			(stroke
				(width 0.1524)
				(type default)
			)
			(layer "B.SilkS")
		)
		(fp_line
			(start -0.7874 0.4064)
			(end 0.7874 0.4064)
			(stroke
				(width 0.1524)
				(type default)
			)
			(layer "B.SilkS")
		)
		(fp_line
			(start 0.67945 -0.305054)
			(end 0.12065 -0.305054)
			(stroke
				(width 0.1)
				(type default)
			)
			(layer "B.Fab")
		)
		(fp_line
			(start 0.12065 -0.305054)
			(end 0.12065 -0.2794)
			(stroke
				(width 0.1)
				(type default)
			)
			(layer "B.Fab")
		)
		(fp_line
			(start -0.12065 -0.3048)
			(end -0.67945 -0.3048)
			(stroke
				(width 0.1)
				(type default)
			)
			(layer "B.Fab")
		)
		(fp_line
			(start -0.67945 -0.3048)
			(end -0.67945 0.3048)
			(stroke
				(width 0.1)
				(type default)
			)
			(layer "B.Fab")
		)
		(fp_line
			(start 0.12065 -0.2794)
			(end -0.12065 -0.2794)
			(stroke
				(width 0.1)
				(type default)
			)
			(layer "B.Fab")
		)
		(fp_line
			(start -0.12065 -0.2794)
			(end -0.12065 -0.3048)
			(stroke
				(width 0.1)
				(type default)
			)
			(layer "B.Fab")
		)
		(fp_line
			(start 0.12065 0.2794)
			(end 0.12065 0.3048)
			(stroke
				(width 0.1)
				(type default)
			)
			(layer "B.Fab")
		)
		(fp_line
			(start -0.120396 0.2794)
			(end 0.12065 0.2794)
			(stroke
				(width 0.1)
				(type default)
			)
			(layer "B.Fab")
		)
		(fp_line
			(start 0.67945 0.3048)
			(end 0.67945 -0.305054)
			(stroke
				(width 0.1)
				(type default)
			)
			(layer "B.Fab")
		)
		(fp_line
			(start 0.12065 0.3048)
			(end 0.67945 0.3048)
			(stroke
				(width 0.1)
				(type default)
			)
			(layer "B.Fab")
		)
		(fp_line
			(start -0.120396 0.3048)
			(end -0.120396 0.2794)
			(stroke
				(width 0.1)
				(type default)
			)
			(layer "B.Fab")
		)
		(fp_line
			(start -0.67945 0.3048)
			(end -0.120396 0.3048)
			(stroke
				(width 0.1)
				(type default)
			)
			(layer "B.Fab")
		)
		(pad "1" smd circle
			(at 0.40005 0 270)
			(size 0 0)
			(layers "B.Cu" "B.Mask" "B.Paste")
			(net "UART_PEX3_CLI_BUF_RX")
		)
		(pad "2" smd circle
			(at -0.40005 0 270)
			(size 0 0)
			(layers "B.Cu" "B.Mask" "B.Paste")
			(net "P1V8_PEX")
		)
	)
	(footprint ""
		(layer "B.Cu")
		(at 404.149814 -290.199826 90)
		(property "Reference" "C1995"
			(at 0 0 90)
			(layer "B.SilkS")
			(hide yes)
			(effects
				(font
					(size 1.27 1.27)
				)
				(justify mirror)
			)
		)
		(property "Value" ""
			(at 0 0 90)
			(layer "B.Fab")
			(effects
				(font
					(size 1.27 1.27)
				)
				(justify mirror)
			)
		)
		(duplicate_pad_numbers_are_jumpers no)
		(fp_line
			(start 0.299974 -0.150114)
			(end -0.299974 -0.150114)
			(stroke
				(width 0.1)
				(type default)
			)
			(layer "B.Fab")
		)
		(fp_line
			(start -0.299974 -0.150114)
			(end -0.299974 0.150114)
			(stroke
				(width 0.1)
				(type default)
			)
			(layer "B.Fab")
		)
		(fp_line
			(start 0.299974 0.150114)
			(end 0.299974 -0.150114)
			(stroke
				(width 0.1)
				(type default)
			)
			(layer "B.Fab")
		)
		(fp_line
			(start -0.299974 0.150114)
			(end 0.299974 0.150114)
			(stroke
				(width 0.1)
				(type default)
			)
			(layer "B.Fab")
		)
		(pad "1" smd rect
			(at 0.2667 0 270)
			(size 0.3048 0.381)
			(layers "B.Cu" "B.Mask" "B.Paste")
			(net "P0V8_SERDES_VDDA_PEX3")
		)
		(pad "2" smd rect
			(at -0.2667 0 270)
			(size 0.3048 0.381)
			(layers "B.Cu" "B.Mask" "B.Paste")
			(net "GND")
		)
	)
	(footprint ""
		(layer "B.Cu")
		(at 353.819968 -284.796738 -90)
		(property "Reference" "PC191"
			(at 0 0 90)
			(layer "B.SilkS")
			(hide yes)
			(effects
				(font
					(size 1.27 1.27)
				)
				(justify mirror)
			)
		)
		(property "Value" ""
			(at 0 0 90)
			(layer "B.Fab")
			(effects
				(font
					(size 1.27 1.27)
				)
				(justify mirror)
			)
		)
		(duplicate_pad_numbers_are_jumpers no)
		(fp_line
			(start -1.524 0.762)
			(end 1.524 0.762)
			(stroke
				(width 0.1524)
				(type default)
			)
			(layer "B.SilkS")
		)
		(fp_line
			(start 1.524 0.762)
			(end 1.524 -0.762)
			(stroke
				(width 0.1524)
				(type default)
			)
			(layer "B.SilkS")
		)
		(fp_line
			(start -1.524 -0.762)
			(end -1.524 0.762)
			(stroke
				(width 0.1524)
				(type default)
			)
			(layer "B.SilkS")
		)
		(fp_line
			(start 1.524 -0.762)
			(end -1.524 -0.762)
			(stroke
				(width 0.1524)
				(type default)
			)
			(layer "B.SilkS")
		)
		(fp_line
			(start -1.1049 0.724916)
			(end -1.1049 -0.724916)
			(stroke
				(width 0.1)
				(type default)
			)
			(layer "B.Fab")
		)
		(fp_line
			(start 1.1049 0.724916)
			(end -1.1049 0.724916)
			(stroke
				(width 0.1)
				(type default)
			)
			(layer "B.Fab")
		)
		(fp_line
			(start -1.1049 -0.724916)
			(end 1.1049 -0.724916)
			(stroke
				(width 0.1)
				(type default)
			)
			(layer "B.Fab")
		)
		(fp_line
			(start 1.1049 -0.724916)
			(end 1.1049 0.724916)
			(stroke
				(width 0.1)
				(type default)
			)
			(layer "B.Fab")
		)
		(pad "1" smd rect
			(at 0.889 0 270)
			(size 1.016 1.27)
			(layers "B.Cu" "B.Mask" "B.Paste")
			(net "SW_P12V_P0V8_PEX3_FLT")
		)
		(pad "2" smd rect
			(at -0.889 0 270)
			(size 1.016 1.27)
			(layers "B.Cu" "B.Mask" "B.Paste")
			(net "GND")
		)
	)
)
